(kicad_pcb
	(version 20260206)
	(generator "pcbnew")
	(generator_version "10.0")
	(general
		(thickness 1.6)
		(legacy_teardrops no)
	)
	(paper "A4")
	(title_block
		(title "04192023_DAF0TMB3IC0_F0TG_MB_C_brd_V02_OCP.brd")
		(comment 1 "Grand Teton / footprints 4234-4240 of 8354")
	)
	(layers
		(0 "F.Cu" signal "TOP")
		(4 "In1.Cu" signal "GND")
		(6 "In2.Cu" signal "IN1")
		(8 "In3.Cu" signal "GND1")
		(10 "In4.Cu" signal "IN2")
		(12 "In5.Cu" signal "GND2")
		(14 "In6.Cu" signal "IN3")
		(16 "In7.Cu" signal "GND3")
		(18 "In8.Cu" signal "VCC")
		(20 "In9.Cu" signal "VCC1")
		(22 "In10.Cu" signal "GND4")
		(24 "In11.Cu" signal "IN4")
		(26 "In12.Cu" signal "GND5")
		(28 "In13.Cu" signal "IN5")
		(30 "In14.Cu" signal "GND6")
		(32 "In15.Cu" signal "IN6")
		(34 "In16.Cu" signal "GND7")
		(2 "B.Cu" signal "BOTTOM")
		(9 "F.Adhes" user "F.Adhesive")
		(11 "B.Adhes" user "B.Adhesive")
		(13 "F.Paste" user "Package Geometry/Pastemask Top")
		(15 "B.Paste" user "Package Geometry/Pastemask Bottom")
		(5 "F.SilkS" user "Ref Des/Silkscreen Top")
		(7 "B.SilkS" user "Ref Des/Silkscreen Bottom")
		(1 "F.Mask" user "Board Geometry/Soldermask Top")
		(3 "B.Mask" user "Board Geometry/Soldermask Bottom")
		(17 "Dwgs.User" user "User.Drawings")
		(19 "Cmts.User" user "User.Comments")
		(21 "Eco1.User" user "User.Eco1")
		(23 "Eco2.User" user "User.Eco2")
		(25 "Edge.Cuts" user "Board Geometry/Outline")
		(27 "Margin" user)
		(31 "F.CrtYd" user "Package Geometry/Place Bound Top")
		(29 "B.CrtYd" user "Package Geometry/Place Bound Bottom")
		(35 "F.Fab" user "Ref Des/Assembly Top")
		(33 "B.Fab" user "Ref Des/Assembly Bottom")
	)
	(footprint ""
		(layer "F.Cu")
		(at 413.303466 -150.858982 90)
		(property "Reference" "PL8065"
			(at 1.033018 -5.987796 90)
			(unlocked yes)
			(layer "F.SilkS")
			(effects
				(font
					(size 0.7874 0.5842)
					(thickness 0.1524)
				)
				(justify left)
			)
		)
		(property "Value" ""
			(at 0 0 90)
			(layer "F.Fab")
			(effects
				(font
					(size 1.27 1.27)
				)
			)
		)
		(duplicate_pad_numbers_are_jumpers no)
		(fp_line
			(start 5.588 -5.150104)
			(end -5.588 -5.150104)
			(stroke
				(width 0.1524)
				(type default)
			)
			(layer "F.SilkS")
		)
		(fp_line
			(start -5.588 -5.150104)
			(end -5.588 -1.8542)
			(stroke
				(width 0.1524)
				(type default)
			)
			(layer "F.SilkS")
		)
		(fp_line
			(start 5.588 -1.8288)
			(end 5.588 -5.150104)
			(stroke
				(width 0.1524)
				(type default)
			)
			(layer "F.SilkS")
		)
		(fp_line
			(start -5.588 1.8288)
			(end -5.588 5.150104)
			(stroke
				(width 0.1524)
				(type default)
			)
			(layer "F.SilkS")
		)
		(fp_line
			(start 5.588 5.150104)
			(end 5.588 1.8034)
			(stroke
				(width 0.1524)
				(type default)
			)
			(layer "F.SilkS")
		)
		(fp_line
			(start -5.588 5.150104)
			(end 5.588 5.150104)
			(stroke
				(width 0.1524)
				(type default)
			)
			(layer "F.SilkS")
		)
		(fp_line
			(start 5.599938 -5.150104)
			(end 5.599938 5.150104)
			(stroke
				(width 0.1)
				(type default)
			)
			(layer "F.Fab")
		)
		(fp_line
			(start -5.599938 -5.150104)
			(end 5.599938 -5.150104)
			(stroke
				(width 0.1)
				(type default)
			)
			(layer "F.Fab")
		)
		(fp_line
			(start 5.599938 5.150104)
			(end -5.599938 5.150104)
			(stroke
				(width 0.1)
				(type default)
			)
			(layer "F.Fab")
		)
		(fp_line
			(start -5.599938 5.150104)
			(end -5.599938 -5.150104)
			(stroke
				(width 0.1)
				(type default)
			)
			(layer "F.Fab")
		)
		(pad "1" smd rect
			(at -4.338828 0 90)
			(size 3.302 3.302)
			(layers "F.Cu" "F.Mask" "F.Paste")
			(net "SW_P5V_AUX_SW")
		)
		(pad "2" smd rect
			(at 4.338828 0 90)
			(size 3.302 3.302)
			(layers "F.Cu" "F.Mask" "F.Paste")
			(net "P5V_AUX")
		)
	)
	(footprint ""
		(layer "F.Cu")
		(at 315.802518 -360.289348)
		(property "Reference" "PC77"
			(at 0 0 0)
			(layer "F.SilkS")
			(hide yes)
			(effects
				(font
					(size 1.27 1.27)
				)
			)
		)
		(property "Value" ""
			(at 0 0 0)
			(layer "F.Fab")
			(effects
				(font
					(size 1.27 1.27)
				)
			)
		)
		(duplicate_pad_numbers_are_jumpers no)
		(fp_line
			(start -0.7874 -0.4064)
			(end 0.7874 -0.4064)
			(stroke
				(width 0.1524)
				(type default)
			)
			(layer "F.SilkS")
		)
		(fp_line
			(start -0.7874 0.4064)
			(end -0.7874 -0.4064)
			(stroke
				(width 0.1524)
				(type default)
			)
			(layer "F.SilkS")
		)
		(fp_line
			(start 0.7874 -0.4064)
			(end 0.7874 0.4064)
			(stroke
				(width 0.1524)
				(type default)
			)
			(layer "F.SilkS")
		)
		(fp_line
			(start 0.7874 0.4064)
			(end -0.7874 0.4064)
			(stroke
				(width 0.1524)
				(type default)
			)
			(layer "F.SilkS")
		)
		(fp_line
			(start -0.67945 -0.305054)
			(end -0.12065 -0.305054)
			(stroke
				(width 0.1)
				(type default)
			)
			(layer "F.Fab")
		)
		(fp_line
			(start -0.67945 0.3048)
			(end -0.67945 -0.305054)
			(stroke
				(width 0.1)
				(type default)
			)
			(layer "F.Fab")
		)
		(fp_line
			(start -0.12065 -0.305054)
			(end -0.12065 -0.2794)
			(stroke
				(width 0.1)
				(type default)
			)
			(layer "F.Fab")
		)
		(fp_line
			(start -0.12065 -0.2794)
			(end 0.12065 -0.2794)
			(stroke
				(width 0.1)
				(type default)
			)
			(layer "F.Fab")
		)
		(fp_line
			(start -0.12065 0.2794)
			(end -0.12065 0.3048)
			(stroke
				(width 0.1)
				(type default)
			)
			(layer "F.Fab")
		)
		(fp_line
			(start -0.12065 0.3048)
			(end -0.67945 0.3048)
			(stroke
				(width 0.1)
				(type default)
			)
			(layer "F.Fab")
		)
		(fp_line
			(start 0.120396 0.2794)
			(end -0.12065 0.2794)
			(stroke
				(width 0.1)
				(type default)
			)
			(layer "F.Fab")
		)
		(fp_line
			(start 0.120396 0.3048)
			(end 0.120396 0.2794)
			(stroke
				(width 0.1)
				(type default)
			)
			(layer "F.Fab")
		)
		(fp_line
			(start 0.12065 -0.3048)
			(end 0.67945 -0.3048)
			(stroke
				(width 0.1)
				(type default)
			)
			(layer "F.Fab")
		)
		(fp_line
			(start 0.12065 -0.2794)
			(end 0.12065 -0.3048)
			(stroke
				(width 0.1)
				(type default)
			)
			(layer "F.Fab")
		)
		(fp_line
			(start 0.67945 -0.3048)
			(end 0.67945 0.3048)
			(stroke
				(width 0.1)
				(type default)
			)
			(layer "F.Fab")
		)
		(fp_line
			(start 0.67945 0.3048)
			(end 0.120396 0.3048)
			(stroke
				(width 0.1)
				(type default)
			)
			(layer "F.Fab")
		)
		(pad "1" smd circle
			(at -0.40005 0)
			(size 0 0)
			(layers "F.Cu" "F.Mask" "F.Paste")
			(net "PVDDIO_P0_TEMP1")
		)
		(pad "2" smd circle
			(at 0.40005 0)
			(size 0 0)
			(layers "F.Cu" "F.Mask" "F.Paste")
			(net "GND")
		)
	)
	(footprint ""
		(layer "F.Cu")
		(at 185.039 -137.632948 90)
		(property "Reference" "R1557"
			(at 0 0 90)
			(layer "F.SilkS")
			(hide yes)
			(effects
				(font
					(size 1.27 1.27)
				)
			)
		)
		(property "Value" ""
			(at 0 0 90)
			(layer "F.Fab")
			(effects
				(font
					(size 1.27 1.27)
				)
			)
		)
		(duplicate_pad_numbers_are_jumpers no)
		(fp_line
			(start 0.7874 -0.4064)
			(end 0.7874 0.4064)
			(stroke
				(width 0.1524)
				(type default)
			)
			(layer "F.SilkS")
		)
		(fp_line
			(start -0.7874 -0.4064)
			(end 0.7874 -0.4064)
			(stroke
				(width 0.1524)
				(type default)
			)
			(layer "F.SilkS")
		)
		(fp_line
			(start 0.7874 0.4064)
			(end -0.7874 0.4064)
			(stroke
				(width 0.1524)
				(type default)
			)
			(layer "F.SilkS")
		)
		(fp_line
			(start -0.7874 0.4064)
			(end -0.7874 -0.4064)
			(stroke
				(width 0.1524)
				(type default)
			)
			(layer "F.SilkS")
		)
		(fp_line
			(start -0.12065 -0.305054)
			(end -0.12065 -0.2794)
			(stroke
				(width 0.1)
				(type default)
			)
			(layer "F.Fab")
		)
		(fp_line
			(start -0.67945 -0.305054)
			(end -0.12065 -0.305054)
			(stroke
				(width 0.1)
				(type default)
			)
			(layer "F.Fab")
		)
		(fp_line
			(start 0.67945 -0.3048)
			(end 0.67945 0.3048)
			(stroke
				(width 0.1)
				(type default)
			)
			(layer "F.Fab")
		)
		(fp_line
			(start 0.12065 -0.3048)
			(end 0.67945 -0.3048)
			(stroke
				(width 0.1)
				(type default)
			)
			(layer "F.Fab")
		)
		(fp_line
			(start 0.12065 -0.2794)
			(end 0.12065 -0.3048)
			(stroke
				(width 0.1)
				(type default)
			)
			(layer "F.Fab")
		)
		(fp_line
			(start -0.12065 -0.2794)
			(end 0.12065 -0.2794)
			(stroke
				(width 0.1)
				(type default)
			)
			(layer "F.Fab")
		)
		(fp_line
			(start 0.120396 0.2794)
			(end -0.12065 0.2794)
			(stroke
				(width 0.1)
				(type default)
			)
			(layer "F.Fab")
		)
		(fp_line
			(start -0.12065 0.2794)
			(end -0.12065 0.3048)
			(stroke
				(width 0.1)
				(type default)
			)
			(layer "F.Fab")
		)
		(fp_line
			(start 0.67945 0.3048)
			(end 0.120396 0.3048)
			(stroke
				(width 0.1)
				(type default)
			)
			(layer "F.Fab")
		)
		(fp_line
			(start 0.120396 0.3048)
			(end 0.120396 0.2794)
			(stroke
				(width 0.1)
				(type default)
			)
			(layer "F.Fab")
		)
		(fp_line
			(start -0.12065 0.3048)
			(end -0.67945 0.3048)
			(stroke
				(width 0.1)
				(type default)
			)
			(layer "F.Fab")
		)
		(fp_line
			(start -0.67945 0.3048)
			(end -0.67945 -0.305054)
			(stroke
				(width 0.1)
				(type default)
			)
			(layer "F.Fab")
		)
		(pad "1" smd circle
			(at -0.40005 0 90)
			(size 0 0)
			(layers "F.Cu" "F.Mask" "F.Paste")
			(net "ESPI_CPU0_ALERT_R_N")
		)
		(pad "2" smd circle
			(at 0.40005 0 90)
			(size 0 0)
			(layers "F.Cu" "F.Mask" "F.Paste")
			(net "ESPI_CPU0_ALERT_PLD_N")
		)
	)
	(footprint ""
		(layer "F.Cu")
		(at 109.577124 -261.748016 -90)
		(property "Reference" "C2121"
			(at 0 0 270)
			(layer "F.SilkS")
			(hide yes)
			(effects
				(font
					(size 1.27 1.27)
				)
			)
		)
		(property "Value" ""
			(at 0 0 270)
			(layer "F.Fab")
			(effects
				(font
					(size 1.27 1.27)
				)
			)
		)
		(duplicate_pad_numbers_are_jumpers no)
		(fp_line
			(start -0.7874 0.4064)
			(end -0.7874 -0.4064)
			(stroke
				(width 0.1524)
				(type default)
			)
			(layer "F.SilkS")
		)
		(fp_line
			(start 0.7874 0.4064)
			(end -0.7874 0.4064)
			(stroke
				(width 0.1524)
				(type default)
			)
			(layer "F.SilkS")
		)
		(fp_line
			(start -0.7874 -0.4064)
			(end 0.7874 -0.4064)
			(stroke
				(width 0.1524)
				(type default)
			)
			(layer "F.SilkS")
		)
		(fp_line
			(start 0.7874 -0.4064)
			(end 0.7874 0.4064)
			(stroke
				(width 0.1524)
				(type default)
			)
			(layer "F.SilkS")
		)
		(fp_line
			(start -0.67945 0.3048)
			(end -0.67945 -0.305054)
			(stroke
				(width 0.1)
				(type default)
			)
			(layer "F.Fab")
		)
		(fp_line
			(start -0.12065 0.3048)
			(end -0.67945 0.3048)
			(stroke
				(width 0.1)
				(type default)
			)
			(layer "F.Fab")
		)
		(fp_line
			(start 0.120396 0.3048)
			(end 0.120396 0.2794)
			(stroke
				(width 0.1)
				(type default)
			)
			(layer "F.Fab")
		)
		(fp_line
			(start 0.67945 0.3048)
			(end 0.120396 0.3048)
			(stroke
				(width 0.1)
				(type default)
			)
			(layer "F.Fab")
		)
		(fp_line
			(start -0.12065 0.2794)
			(end -0.12065 0.3048)
			(stroke
				(width 0.1)
				(type default)
			)
			(layer "F.Fab")
		)
		(fp_line
			(start 0.120396 0.2794)
			(end -0.12065 0.2794)
			(stroke
				(width 0.1)
				(type default)
			)
			(layer "F.Fab")
		)
		(fp_line
			(start -0.12065 -0.2794)
			(end 0.12065 -0.2794)
			(stroke
				(width 0.1)
				(type default)
			)
			(layer "F.Fab")
		)
		(fp_line
			(start 0.12065 -0.2794)
			(end 0.12065 -0.3048)
			(stroke
				(width 0.1)
				(type default)
			)
			(layer "F.Fab")
		)
		(fp_line
			(start 0.12065 -0.3048)
			(end 0.67945 -0.3048)
			(stroke
				(width 0.1)
				(type default)
			)
			(layer "F.Fab")
		)
		(fp_line
			(start 0.67945 -0.3048)
			(end 0.67945 0.3048)
			(stroke
				(width 0.1)
				(type default)
			)
			(layer "F.Fab")
		)
		(fp_line
			(start -0.67945 -0.305054)
			(end -0.12065 -0.305054)
			(stroke
				(width 0.1)
				(type default)
			)
			(layer "F.Fab")
		)
		(fp_line
			(start -0.12065 -0.305054)
			(end -0.12065 -0.2794)
			(stroke
				(width 0.1)
				(type default)
			)
			(layer "F.Fab")
		)
		(pad "1" smd circle
			(at -0.40005 0 270)
			(size 0 0)
			(layers "F.Cu" "F.Mask" "F.Paste")
			(net "PVDD11_S3_P1")
		)
		(pad "2" smd circle
			(at 0.40005 0 270)
			(size 0 0)
			(layers "F.Cu" "F.Mask" "F.Paste")
			(net "GND")
		)
	)
	(footprint ""
		(layer "F.Cu")
		(at 255.13284 -92.719144 -90)
		(property "Reference" "C1516"
			(at 0 0 270)
			(layer "F.SilkS")
			(hide yes)
			(effects
				(font
					(size 1.27 1.27)
				)
			)
		)
		(property "Value" ""
			(at 0 0 270)
			(layer "F.Fab")
			(effects
				(font
					(size 1.27 1.27)
				)
			)
		)
		(duplicate_pad_numbers_are_jumpers no)
		(fp_line
			(start -0.7874 0.4064)
			(end -0.7874 -0.4064)
			(stroke
				(width 0.1524)
				(type default)
			)
			(layer "F.SilkS")
		)
		(fp_line
			(start 0.7874 0.4064)
			(end -0.7874 0.4064)
			(stroke
				(width 0.1524)
				(type default)
			)
			(layer "F.SilkS")
		)
		(fp_line
			(start -0.7874 -0.4064)
			(end 0.7874 -0.4064)
			(stroke
				(width 0.1524)
				(type default)
			)
			(layer "F.SilkS")
		)
		(fp_line
			(start 0.7874 -0.4064)
			(end 0.7874 0.4064)
			(stroke
				(width 0.1524)
				(type default)
			)
			(layer "F.SilkS")
		)
		(fp_line
			(start -0.67945 0.3048)
			(end -0.67945 -0.305054)
			(stroke
				(width 0.1)
				(type default)
			)
			(layer "F.Fab")
		)
		(fp_line
			(start -0.12065 0.3048)
			(end -0.67945 0.3048)
			(stroke
				(width 0.1)
				(type default)
			)
			(layer "F.Fab")
		)
		(fp_line
			(start 0.120396 0.3048)
			(end 0.120396 0.2794)
			(stroke
				(width 0.1)
				(type default)
			)
			(layer "F.Fab")
		)
		(fp_line
			(start 0.67945 0.3048)
			(end 0.120396 0.3048)
			(stroke
				(width 0.1)
				(type default)
			)
			(layer "F.Fab")
		)
		(fp_line
			(start -0.12065 0.2794)
			(end -0.12065 0.3048)
			(stroke
				(width 0.1)
				(type default)
			)
			(layer "F.Fab")
		)
		(fp_line
			(start 0.120396 0.2794)
			(end -0.12065 0.2794)
			(stroke
				(width 0.1)
				(type default)
			)
			(layer "F.Fab")
		)
		(fp_line
			(start -0.12065 -0.2794)
			(end 0.12065 -0.2794)
			(stroke
				(width 0.1)
				(type default)
			)
			(layer "F.Fab")
		)
		(fp_line
			(start 0.12065 -0.2794)
			(end 0.12065 -0.3048)
			(stroke
				(width 0.1)
				(type default)
			)
			(layer "F.Fab")
		)
		(fp_line
			(start 0.12065 -0.3048)
			(end 0.67945 -0.3048)
			(stroke
				(width 0.1)
				(type default)
			)
			(layer "F.Fab")
		)
		(fp_line
			(start 0.67945 -0.3048)
			(end 0.67945 0.3048)
			(stroke
				(width 0.1)
				(type default)
			)
			(layer "F.Fab")
		)
		(fp_line
			(start -0.67945 -0.305054)
			(end -0.12065 -0.305054)
			(stroke
				(width 0.1)
				(type default)
			)
			(layer "F.Fab")
		)
		(fp_line
			(start -0.12065 -0.305054)
			(end -0.12065 -0.2794)
			(stroke
				(width 0.1)
				(type default)
			)
			(layer "F.Fab")
		)
		(pad "1" smd circle
			(at -0.40005 0 270)
			(size 0 0)
			(layers "F.Cu" "F.Mask" "F.Paste")
			(net "PVDD18_S5_P0")
		)
		(pad "2" smd circle
			(at 0.40005 0 270)
			(size 0 0)
			(layers "F.Cu" "F.Mask" "F.Paste")
			(net "GND")
		)
	)
	(footprint ""
		(layer "F.Cu")
		(at 326.967342 -391.0584 180)
		(property "Reference" "R968"
			(at 0 0 180)
			(layer "F.SilkS")
			(hide yes)
			(effects
				(font
					(size 1.27 1.27)
				)
			)
		)
		(property "Value" ""
			(at 0 0 180)
			(layer "F.Fab")
			(effects
				(font
					(size 1.27 1.27)
				)
			)
		)
		(duplicate_pad_numbers_are_jumpers no)
		(fp_line
			(start 0.32512 0.175006)
			(end -0.32512 0.175006)
			(stroke
				(width 0.1)
				(type default)
			)
			(layer "F.Fab")
		)
		(fp_line
			(start 0.32512 -0.175006)
			(end 0.32512 0.175006)
			(stroke
				(width 0.1)
				(type default)
			)
			(layer "F.Fab")
		)
		(fp_line
			(start -0.32512 0.175006)
			(end -0.32512 -0.175006)
			(stroke
				(width 0.1)
				(type default)
			)
			(layer "F.Fab")
		)
		(fp_line
			(start -0.32512 -0.175006)
			(end 0.32512 -0.175006)
			(stroke
				(width 0.1)
				(type default)
			)
			(layer "F.Fab")
		)
		(pad "1" smd rect
			(at -0.2667 0 180)
			(size 0.3048 0.381)
			(layers "F.Cu" "F.Mask" "F.Paste")
			(net "P1V8_CPU0_RT_1D")
		)
		(pad "2" smd rect
			(at 0.2667 0)
			(size 0.3048 0.381)
			(layers "F.Cu" "F.Mask" "F.Paste")
			(net "RT_CPU0_P0_ADDR1")
		)
	)
	(footprint ""
		(layer "F.Cu")
		(at 157.146244 -373.03583 -90)
		(property "Reference" "C756"
			(at 0 0 270)
			(layer "F.SilkS")
			(hide yes)
			(effects
				(font
					(size 1.27 1.27)
				)
			)
		)
		(property "Value" ""
			(at 0 0 270)
			(layer "F.Fab")
			(effects
				(font
					(size 1.27 1.27)
				)
			)
		)
		(duplicate_pad_numbers_are_jumpers no)
		(fp_line
			(start -0.299974 0.150114)
			(end -0.299974 -0.150114)
			(stroke
				(width 0.1)
				(type default)
			)
			(layer "F.Fab")
		)
		(fp_line
			(start 0.299974 0.150114)
			(end -0.299974 0.150114)
			(stroke
				(width 0.1)
				(type default)
			)
			(layer "F.Fab")
		)
		(fp_line
			(start -0.299974 -0.150114)
			(end 0.299974 -0.150114)
			(stroke
				(width 0.1)
				(type default)
			)
			(layer "F.Fab")
		)
		(fp_line
			(start 0.299974 -0.150114)
			(end 0.299974 0.150114)
			(stroke
				(width 0.1)
				(type default)
			)
			(layer "F.Fab")
		)
		(pad "1" smd rect
			(at -0.2667 0 270)
			(size 0.3048 0.381)
			(layers "F.Cu" "F.Mask" "F.Paste")
			(net "P5E_CPU1_P2_TX_C_DN<8>")
		)
		(pad "2" smd rect
			(at 0.2667 0 270)
			(size 0.3048 0.381)
			(layers "F.Cu" "F.Mask" "F.Paste")
			(net "P5E_CPU1_P2_TX_DN<8>")
		)
	)
)
